(kicad_pcb
	(version 20241229)
	(generator "pcbnew")
	(generator_version "9.0")
	(general
		(thickness 1.63)
		(legacy_teardrops no)
	)
	(paper "A4")
	(title_block
		(title "CM4 Baseboard")
		(date "2026-01-05")
		(rev "1.1.1")
		(company "Antmicro Ltd")
		(comment 1 "www.antmicro.com")
		(comment 9 "footprints 441-444 of 506")
	)
	(layers
		(0 "F.Cu" signal)
		(4 "In1.Cu" power)
		(6 "In2.Cu" power)
		(8 "In3.Cu" signal)
		(10 "In4.Cu" signal)
		(2 "B.Cu" signal)
		(9 "F.Adhes" user "F.Adhesive")
		(11 "B.Adhes" user "B.Adhesive")
		(13 "F.Paste" user)
		(15 "B.Paste" user)
		(5 "F.SilkS" user "F.Silkscreen")
		(7 "B.SilkS" user "B.Silkscreen")
		(1 "F.Mask" user)
		(3 "B.Mask" user)
		(17 "Dwgs.User" user "User.Drawings")
		(19 "Cmts.User" user "User.Comments")
		(21 "Eco1.User" user "User.Eco1")
		(23 "Eco2.User" user "User.Eco2")
		(25 "Edge.Cuts" user)
		(27 "Margin" user)
		(31 "F.CrtYd" user "F.Courtyard")
		(29 "B.CrtYd" user "B.Courtyard")
		(35 "F.Fab" user)
		(33 "B.Fab" user)
	)
	(footprint "antmicro-footprints:R_Array_4x0402_Panasonic_EXB28V"
		(layer "B.Cu")
		(at 110.087962 118.9265)
		(property "Reference" "R701"
			(at -4.26 0.42 0)
			(layer "B.SilkS")
			(effects
				(font
					(size 0.7 0.7)
					(thickness 0.15)
				)
				(justify right bottom mirror)
			)
		)
		(property "Value" "R_4x100R_0402_array"
			(at -1.5 -2 0)
			(layer "B.Fab")
			(effects
				(font
					(size 0.7 0.7)
					(thickness 0.15)
				)
				(justify right bottom mirror)
			)
		)
		(property "Datasheet" "http://industrial.panasonic.com/cdbs/www-data/pdf/AOC0000/AOC0000C14.pdf"
			(at 0 0 0)
			(layer "B.Fab")
			(hide yes)
			(effects
				(font
					(size 1.27 1.27)
					(thickness 0.15)
				)
			)
		)
		(property "MPN" "EXB-28V101JX"
			(at 0 0 0)
			(unlocked yes)
			(layer "B.Fab")
			(hide yes)
			(effects
				(font
					(size 1 1)
					(thickness 0.15)
				)
				(justify mirror)
			)
		)
		(property "Manufacturer" "Panasonic"
			(at 0 0 0)
			(unlocked yes)
			(layer "B.Fab")
			(hide yes)
			(effects
				(font
					(size 1 1)
					(thickness 0.15)
				)
				(justify mirror)
			)
		)
		(property "License" "Apache-2.0"
			(at 0 0 0)
			(unlocked yes)
			(layer "B.Fab")
			(hide yes)
			(effects
				(font
					(size 1 1)
					(thickness 0.15)
				)
				(justify mirror)
			)
		)
		(property "Author" "Antmicro"
			(at 0 0 0)
			(unlocked yes)
			(layer "B.Fab")
			(hide yes)
			(effects
				(font
					(size 1 1)
					(thickness 0.15)
				)
				(justify mirror)
			)
		)
		(property "Val" "R_4x100R_0402"
			(at 0 0 0)
			(unlocked yes)
			(layer "B.Fab")
			(hide yes)
			(effects
				(font
					(size 1 1)
					(thickness 0.15)
				)
				(justify mirror)
			)
		)
		(sheetname "/Display/")
		(sheetfile "display.kicad_sch")
		(attr smd)
		(fp_line
			(start -1.25 0.5)
			(end -1.25 -0.498)
			(stroke
				(width 0.15)
				(type solid)
			)
			(layer "B.SilkS")
		)
		(fp_line
			(start 1.25 -0.499)
			(end 1.25 0.499)
			(stroke
				(width 0.15)
				(type solid)
			)
			(layer "B.SilkS")
		)
		(fp_rect
			(start -1.25 0.8)
			(end 1.25 -0.8)
			(stroke
				(width 0.05)
				(type solid)
			)
			(fill no)
			(layer "B.CrtYd")
		)
		(fp_line
			(start -1 -0.498)
			(end -1 0.5)
			(stroke
				(width 0.15)
				(type solid)
			)
			(layer "B.Fab")
		)
		(fp_line
			(start -1 0.5)
			(end 0.998 0.5)
			(stroke
				(width 0.15)
				(type solid)
			)
			(layer "B.Fab")
		)
		(fp_line
			(start 0.998 -0.498)
			(end -1 -0.498)
			(stroke
				(width 0.15)
				(type solid)
			)
			(layer "B.Fab")
		)
		(fp_line
			(start 0.998 0.5)
			(end 0.998 -0.498)
			(stroke
				(width 0.15)
				(type solid)
			)
			(layer "B.Fab")
		)
		(fp_text user "License: Apache-2.0"
			(at -1.5 -5.75 180)
			(layer "B.Fab")
			(effects
				(font
					(size 0.7 0.7)
					(thickness 0.15)
				)
				(justify left bottom mirror)
			)
		)
		(fp_text user "${REFERENCE}"
			(at -1.5 -3.25 180)
			(layer "B.Fab")
			(effects
				(font
					(size 0.7 0.7)
					(thickness 0.15)
				)
				(justify left bottom mirror)
			)
		)
		(fp_text user "Author: Antmicro"
			(at -1.5 -4.5 180)
			(layer "B.Fab")
			(effects
				(font
					(size 0.7 0.7)
					(thickness 0.15)
				)
				(justify left bottom mirror)
			)
		)
		(pad "1" smd roundrect
			(at -0.8875 -0.45)
			(size 0.525 0.5)
			(layers "B.Cu" "B.Mask" "B.Paste")
			(roundrect_rratio 0.25)
			(net 266 "/Compute module/HDMI.SDA")
			(pinfunction "R1.1")
			(pintype "passive")
		)
		(pad "2" smd roundrect
			(at -0.25 -0.45)
			(size 0.25 0.5)
			(layers "B.Cu" "B.Mask" "B.Paste")
			(roundrect_rratio 0.25)
			(net 267 "/Compute module/HDMI.SCL")
			(pinfunction "R2.1")
			(pintype "passive")
		)
		(pad "3" smd roundrect
			(at 0.25 -0.45)
			(size 0.25 0.5)
			(layers "B.Cu" "B.Mask" "B.Paste")
			(roundrect_rratio 0.25)
			(net 261 "/Compute module/HDMI.CEC")
			(pinfunction "R3.1")
			(pintype "passive")
		)
		(pad "4" smd roundrect
			(at 0.8875 -0.45)
			(size 0.525 0.5)
			(layers "B.Cu" "B.Mask" "B.Paste")
			(roundrect_rratio 0.25)
			(net 262 "/Compute module/HDMI.HPD")
			(pinfunction "R4.1")
			(pintype "passive")
		)
		(pad "5" smd roundrect
			(at 0.8875 0.45)
			(size 0.525 0.5)
			(layers "B.Cu" "B.Mask" "B.Paste")
			(roundrect_rratio 0.25)
			(net 454 "/Display/HPD")
			(pinfunction "R4.2")
			(pintype "passive")
		)
		(pad "6" smd roundrect
			(at 0.25 0.45)
			(size 0.25 0.5)
			(layers "B.Cu" "B.Mask" "B.Paste")
			(roundrect_rratio 0.25)
			(net 451 "/Display/CEC")
			(pinfunction "R3.2")
			(pintype "passive")
		)
		(pad "7" smd roundrect
			(at -0.25 0.45)
			(size 0.25 0.5)
			(layers "B.Cu" "B.Mask" "B.Paste")
			(roundrect_rratio 0.25)
			(net 452 "/Display/SCL")
			(pinfunction "R2.2")
			(pintype "passive")
		)
		(pad "8" smd roundrect
			(at -0.8875 0.45)
			(size 0.525 0.5)
			(layers "B.Cu" "B.Mask" "B.Paste")
			(roundrect_rratio 0.25)
			(net 453 "/Display/SDA")
			(pinfunction "R1.2")
			(pintype "passive")
		)
	)
	(footprint "antmicro-footprints:SOD-523"
		(layer "B.Cu")
		(at 125.6 178.7 180)
		(property "Reference" "D811"
			(at -1.3 0.7 0)
			(layer "B.SilkS")
			(effects
				(font
					(size 0.7 0.7)
					(thickness 0.15)
				)
				(justify left bottom mirror)
			)
		)
		(property "Value" "RB521S30T1G"
			(at 0 -1.499 0)
			(layer "B.Fab")
			(effects
				(font
					(size 0.7 0.7)
					(thickness 0.15)
				)
				(justify left bottom mirror)
			)
		)
		(property "Datasheet" "https://www.onsemi.com/pdf/datasheet/rb521s30t1-d.pdf"
			(at 0 0 0)
			(layer "B.Fab")
			(hide yes)
			(effects
				(font
					(size 1.27 1.27)
					(thickness 0.15)
				)
				(justify mirror)
			)
		)
		(property "MPN" "RB521S30T1G"
			(at 0 0 180)
			(unlocked yes)
			(layer "B.Fab")
			(hide yes)
			(effects
				(font
					(size 1 1)
					(thickness 0.15)
				)
				(justify mirror)
			)
		)
		(property "Manufacturer" "ON Semiconductor"
			(at 0 0 180)
			(unlocked yes)
			(layer "B.Fab")
			(hide yes)
			(effects
				(font
					(size 1 1)
					(thickness 0.15)
				)
				(justify mirror)
			)
		)
		(property "Author" "Antmicro"
			(at 0 0 180)
			(unlocked yes)
			(layer "B.Fab")
			(hide yes)
			(effects
				(font
					(size 1 1)
					(thickness 0.15)
				)
				(justify mirror)
			)
		)
		(property "License" "Apache-2.0"
			(at 0 0 180)
			(unlocked yes)
			(layer "B.Fab")
			(hide yes)
			(effects
				(font
					(size 1 1)
					(thickness 0.15)
				)
				(justify mirror)
			)
		)
		(sheetname "/Peripherals/")
		(sheetfile "peripherals.kicad_sch")
		(attr smd)
		(fp_line
			(start -0.35 0.5)
			(end -0.35 -0.5)
			(stroke
				(width 0.15)
				(type solid)
			)
			(layer "B.SilkS")
		)
		(fp_rect
			(start -1 0.6)
			(end 1 -0.6)
			(stroke
				(width 0.05)
				(type solid)
			)
			(fill no)
			(layer "B.CrtYd")
		)
		(fp_line
			(start 0.65 0.425)
			(end 0.65 -0.423)
			(stroke
				(width 0.15)
				(type solid)
			)
			(layer "B.Fab")
		)
		(fp_line
			(start -0.35 0.4)
			(end -0.35 -0.4)
			(stroke
				(width 0.15)
				(type solid)
			)
			(layer "B.Fab")
		)
		(fp_line
			(start -0.652 0.425)
			(end 0.65 0.425)
			(stroke
				(width 0.15)
				(type solid)
			)
			(layer "B.Fab")
		)
		(fp_line
			(start -0.652 -0.423)
			(end 0.65 -0.423)
			(stroke
				(width 0.15)
				(type solid)
			)
			(layer "B.Fab")
		)
		(fp_line
			(start -0.652 -0.423)
			(end -0.652 0.425)
			(stroke
				(width 0.15)
				(type solid)
			)
			(layer "B.Fab")
		)
		(fp_text user "Author: Antmicro"
			(at -1.276 -4.7 0)
			(layer "B.Fab")
			(effects
				(font
					(size 0.7 0.7)
					(thickness 0.15)
				)
				(justify left bottom mirror)
			)
		)
		(fp_text user "${REFERENCE}"
			(at -1.276 -3.499 0)
			(layer "B.Fab")
			(effects
				(font
					(size 0.7 0.7)
					(thickness 0.15)
				)
				(justify left bottom mirror)
			)
		)
		(fp_text user "License: Apache-2.0"
			(at -1.276 -5.9 0)
			(layer "B.Fab")
			(effects
				(font
					(size 0.7 0.7)
					(thickness 0.15)
				)
				(justify left bottom mirror)
			)
		)
		(pad "1" smd roundrect
			(at -0.701 0 180)
			(size 0.5 0.6)
			(layers "B.Cu" "B.Mask" "B.Paste")
			(roundrect_rratio 0.25)
			(net 503 "Net-(D811-C)")
			(pinfunction "C")
			(pintype "passive")
		)
		(pad "2" smd roundrect
			(at 0.699 0 180)
			(size 0.5 0.6)
			(layers "B.Cu" "B.Mask" "B.Paste")
			(roundrect_rratio 0.25)
			(net 9 "+3V3")
			(pinfunction "A")
			(pintype "passive")
		)
	)
	(footprint "antmicro-footprints:TP_SMD_0.75mm"
		(layer "B.Cu")
		(at 82.617962 166.2165)
		(property "Reference" "TP202"
			(at -0.81 1.32 0)
			(layer "B.SilkS")
			(effects
				(font
					(size 0.7 0.7)
					(thickness 0.15)
				)
				(justify right bottom mirror)
			)
		)
		(property "Value" "TP_0.75mm_SMD"
			(at 0 -1.2 0)
			(layer "B.Fab")
			(effects
				(font
					(size 0.7 0.7)
					(thickness 0.15)
				)
				(justify right bottom mirror)
			)
		)
		(property "Author" "Antmicro"
			(at 0 0 0)
			(unlocked yes)
			(layer "B.Fab")
			(hide yes)
			(effects
				(font
					(size 1 1)
					(thickness 0.15)
				)
				(justify mirror)
			)
		)
		(property "License" "Apache-2.0"
			(at 0 0 0)
			(unlocked yes)
			(layer "B.Fab")
			(hide yes)
			(effects
				(font
					(size 1 1)
					(thickness 0.15)
				)
				(justify mirror)
			)
		)
		(property "MPN" ""
			(at 0 0 0)
			(unlocked yes)
			(layer "B.Fab")
			(hide yes)
			(effects
				(font
					(size 1 1)
					(thickness 0.15)
				)
				(justify mirror)
			)
		)
		(property "Manufacturer" ""
			(at 0 0 0)
			(unlocked yes)
			(layer "B.Fab")
			(hide yes)
			(effects
				(font
					(size 1 1)
					(thickness 0.15)
				)
				(justify mirror)
			)
		)
		(sheetname "/Compute module/")
		(sheetfile "compute-module.kicad_sch")
		(attr exclude_from_pos_files exclude_from_bom)
		(fp_circle
			(center 0 0)
			(end 0.475 0)
			(stroke
				(width 0.05)
				(type default)
			)
			(fill no)
			(layer "B.CrtYd")
		)
		(fp_text user "Author: Antmicro"
			(at -0.4 -3.901 180)
			(layer "B.Fab")
			(effects
				(font
					(size 0.7 0.7)
					(thickness 0.15)
				)
				(justify left bottom mirror)
			)
		)
		(fp_text user "${REFERENCE}"
			(at -0.4 -2.7 180)
			(layer "B.Fab")
			(effects
				(font
					(size 0.7 0.7)
					(thickness 0.15)
				)
				(justify left bottom mirror)
			)
		)
		(fp_text user "License: Apache-2.0"
			(at -0.4 -5.101 180)
			(layer "B.Fab")
			(effects
				(font
					(size 0.7 0.7)
					(thickness 0.15)
				)
				(justify left bottom mirror)
			)
		)
		(pad "1" smd circle
			(at 0 0)
			(size 0.75 0.75)
			(layers "B.Cu" "B.Mask")
			(net 128 "/Compute module/nEXTRST")
			(pinfunction "1")
			(pintype "passive")
		)
	)
	(footprint "antmicro-footprints:V-QFN2030-12"
		(layer "B.Cu")
		(at 54.167962 155.8165 -90)
		(property "Reference" "U303"
			(at -5.43 2.46 90)
			(layer "B.SilkS")
			(effects
				(font
					(size 0.7 0.7)
					(thickness 0.15)
				)
				(justify left bottom mirror)
			)
		)
		(property "Value" "AP62600SJ-7"
			(at -4 -2.2 90)
			(layer "B.Fab")
			(effects
				(font
					(size 0.7 0.7)
					(thickness 0.15)
				)
				(justify left bottom mirror)
			)
		)
		(property "Datasheet" "https://www.diodes.com/assets/Datasheets/AP62600.pdf"
			(at 0 0 90)
			(layer "B.Fab")
			(hide yes)
			(effects
				(font
					(size 1.27 1.27)
					(thickness 0.15)
				)
			)
		)
		(property "MPN" "AP62600SJ-7"
			(at 0 0 270)
			(unlocked yes)
			(layer "B.Fab")
			(hide yes)
			(effects
				(font
					(size 1 1)
					(thickness 0.15)
				)
				(justify mirror)
			)
		)
		(property "Manufacturer" "Diodes Incorporated"
			(at 0 0 270)
			(unlocked yes)
			(layer "B.Fab")
			(hide yes)
			(effects
				(font
					(size 1 1)
					(thickness 0.15)
				)
				(justify mirror)
			)
		)
		(property "Author" "Antmicro"
			(at 0 0 270)
			(unlocked yes)
			(layer "B.Fab")
			(hide yes)
			(effects
				(font
					(size 1 1)
					(thickness 0.15)
				)
				(justify mirror)
			)
		)
		(property "License" "Apache-2.0"
			(at 0 0 270)
			(unlocked yes)
			(layer "B.Fab")
			(hide yes)
			(effects
				(font
					(size 1 1)
					(thickness 0.15)
				)
				(justify mirror)
			)
		)
		(sheetname "/Supply/")
		(sheetfile "supply.kicad_sch")
		(attr smd)
		(fp_line
			(start 1.8 1.276)
			(end 1.8 1.025)
			(stroke
				(width 0.15)
				(type solid)
			)
			(layer "B.SilkS")
		)
		(fp_line
			(start -1.801 1.2)
			(end -0.802 1.2)
			(stroke
				(width 0.15)
				(type solid)
			)
			(layer "B.SilkS")
		)
		(fp_line
			(start -1.801 1)
			(end -1.801 1.2)
			(stroke
				(width 0.15)
				(type solid)
			)
			(layer "B.SilkS")
		)
		(fp_line
			(start 1.8 -0.998)
			(end 1.8 -1.199)
			(stroke
				(width 0.15)
				(type solid)
			)
			(layer "B.SilkS")
		)
		(fp_line
			(start -1.801 -1.199)
			(end -1.801 -0.998)
			(stroke
				(width 0.15)
				(type solid)
			)
			(layer "B.SilkS")
		)
		(fp_line
			(start -0.802 -1.199)
			(end -1.801 -1.199)
			(stroke
				(width 0.15)
				(type solid)
			)
			(layer "B.SilkS")
		)
		(fp_line
			(start 1.8 -1.199)
			(end 0.8 -1.199)
			(stroke
				(width 0.15)
				(type solid)
			)
			(layer "B.SilkS")
		)
		(fp_circle
			(center 0.497 1.7)
			(end 0.548 1.7)
			(stroke
				(width 0.15)
				(type solid)
			)
			(fill yes)
			(layer "B.SilkS")
		)
		(fp_rect
			(start -2.026 1.525)
			(end 2.023 -1.524)
			(stroke
				(width 0.05)
				(type solid)
			)
			(fill no)
			(layer "B.CrtYd")
		)
		(fp_line
			(start 1.3 1)
			(end 1.5 0.8)
			(stroke
				(width 0.15)
				(type solid)
			)
			(layer "B.Fab")
		)
		(fp_rect
			(start -1.526 1.025)
			(end 1.523 -1.024)
			(stroke
				(width 0.15)
				(type solid)
			)
			(fill no)
			(layer "B.Fab")
		)
		(fp_text user "${REFERENCE}"
			(at -4 -4.2 90)
			(layer "B.Fab")
			(effects
				(font
					(size 0.7 0.7)
					(thickness 0.15)
				)
				(justify left bottom mirror)
			)
		)
		(fp_text user "License: Apache-2.0"
			(at -4 -6.6 90)
			(layer "B.Fab")
			(effects
				(font
					(size 0.7 0.7)
					(thickness 0.15)
				)
				(justify left bottom mirror)
			)
		)
		(fp_text user "Author: Antmicro"
			(at -4 -5.4 90)
			(layer "B.Fab")
			(effects
				(font
					(size 0.7 0.7)
					(thickness 0.15)
				)
				(justify left bottom mirror)
			)
		)
		(pad "1" smd rect
			(at 0.498 0.552)
			(size 1.6 0.35)
			(layers "B.Cu" "B.Mask" "B.Paste")
			(net 3 "GND")
			(pinfunction "PGND")
			(pintype "passive")
		)
		(pad "2" smd rect
			(at -0.5 0.552)
			(size 1.6 0.35)
			(layers "B.Cu" "B.Mask" "B.Paste")
			(net 43 "VCC")
			(pinfunction "VIN")
			(pintype "power_in")
		)
		(pad "3" smd rect
			(at -1.45 0.75)
			(size 0.35 0.8)
			(layers "B.Cu" "B.Mask" "B.Paste")
			(net 351 "/Supply/EN_5V")
			(pinfunction "EN")
			(pintype "input")
		)
		(pad "4" smd rect
			(at -1.45 0.25)
			(size 0.35 0.8)
			(layers "B.Cu" "B.Mask" "B.Paste")
			(net 390 "unconnected-(U303-MODE-Pad4)")
			(pinfunction "MODE")
			(pintype "input+no_connect")
		)
		(pad "5" smd rect
			(at -1.45 -0.248)
			(size 0.35 0.8)
			(layers "B.Cu" "B.Mask" "B.Paste")
			(net 391 "unconnected-(U303-FSEL-Pad5)")
			(pinfunction "FSEL")
			(pintype "input+no_connect")
		)
		(pad "6" smd rect
			(at -1.45 -0.748)
			(size 0.35 0.8)
			(layers "B.Cu" "B.Mask" "B.Paste")
			(net 352 "Net-(U303-PG)")
			(pinfunction "PG")
			(pintype "open_collector")
		)
		(pad "7" smd rect
			(at -0.5 -0.949 270)
			(size 0.35 0.8)
			(layers "B.Cu" "B.Mask" "B.Paste")
			(net 60 "Net-(U303-BST)")
			(pinfunction "BST")
			(pintype "input")
		)
		(pad "8" smd rect
			(at 0 -0.55)
			(size 1.6 0.35)
			(layers "B.Cu" "B.Mask" "B.Paste")
			(net 59 "/Supply/SW_5V")
			(pinfunction "SW")
			(pintype "output")
		)
		(pad "9" smd rect
			(at 1.449 -0.748 180)
			(size 0.35 0.8)
			(layers "B.Cu" "B.Mask" "B.Paste")
			(net 66 "/Supply/VCC_5V")
			(pinfunction "VCC")
			(pintype "input")
		)
		(pad "10" smd rect
			(at 1.449 -0.248 180)
			(size 0.35 0.8)
			(layers "B.Cu" "B.Mask" "B.Paste")
			(net 392 "unconnected-(U303-SS{slash}TR-Pad10)")
			(pinfunction "SS/TR")
			(pintype "input+no_connect")
		)
		(pad "11" smd rect
			(at 1.449 0.25 180)
			(size 0.35 0.8)
			(layers "B.Cu" "B.Mask" "B.Paste")
			(net 3 "GND")
			(pinfunction "GND")
			(pintype "passive")
		)
		(pad "12" smd rect
			(at 1.449 0.75 180)
			(size 0.35 0.8)
			(layers "B.Cu" "B.Mask" "B.Paste")
			(net 353 "/Supply/FB_5V")
			(pinfunction "FB")
			(pintype "input")
		)
	)
)
